(kicad_pcb
	(version 20260206)
	(generator "pcbnew")
	(generator_version "10.0")
	(general
		(thickness 1.6)
		(legacy_teardrops no)
	)
	(paper "A4")
	(title_block
		(title "04192023_DAF0TMB3IC0_F0TG_MB_C_brd_V02_OCP.brd")
		(comment 1 "Grand Teton / footprints 5977-5985 of 8354")
	)
	(layers
		(0 "F.Cu" signal "TOP")
		(4 "In1.Cu" signal "GND")
		(6 "In2.Cu" signal "IN1")
		(8 "In3.Cu" signal "GND1")
		(10 "In4.Cu" signal "IN2")
		(12 "In5.Cu" signal "GND2")
		(14 "In6.Cu" signal "IN3")
		(16 "In7.Cu" signal "GND3")
		(18 "In8.Cu" signal "VCC")
		(20 "In9.Cu" signal "VCC1")
		(22 "In10.Cu" signal "GND4")
		(24 "In11.Cu" signal "IN4")
		(26 "In12.Cu" signal "GND5")
		(28 "In13.Cu" signal "IN5")
		(30 "In14.Cu" signal "GND6")
		(32 "In15.Cu" signal "IN6")
		(34 "In16.Cu" signal "GND7")
		(2 "B.Cu" signal "BOTTOM")
		(9 "F.Adhes" user "F.Adhesive")
		(11 "B.Adhes" user "B.Adhesive")
		(13 "F.Paste" user "Package Geometry/Pastemask Top")
		(15 "B.Paste" user "Package Geometry/Pastemask Bottom")
		(5 "F.SilkS" user "Ref Des/Silkscreen Top")
		(7 "B.SilkS" user "Ref Des/Silkscreen Bottom")
		(1 "F.Mask" user "Board Geometry/Soldermask Top")
		(3 "B.Mask" user "Board Geometry/Soldermask Bottom")
		(17 "Dwgs.User" user "User.Drawings")
		(19 "Cmts.User" user "User.Comments")
		(21 "Eco1.User" user "User.Eco1")
		(23 "Eco2.User" user "User.Eco2")
		(25 "Edge.Cuts" user "Board Geometry/Outline")
		(27 "Margin" user)
		(31 "F.CrtYd" user "Package Geometry/Place Bound Top")
		(29 "B.CrtYd" user "Package Geometry/Place Bound Bottom")
		(35 "F.Fab" user "Ref Des/Assembly Top")
		(33 "B.Fab" user "Ref Des/Assembly Bottom")
	)
	(footprint ""
		(layer "B.Cu")
		(at 328.052176 -395.127988 -90)
		(property "Reference" "C511"
			(at 0 0 90)
			(layer "B.SilkS")
			(hide yes)
			(effects
				(font
					(size 1.27 1.27)
				)
				(justify mirror)
			)
		)
		(property "Value" ""
			(at 0 0 90)
			(layer "B.Fab")
			(effects
				(font
					(size 1.27 1.27)
				)
				(justify mirror)
			)
		)
		(duplicate_pad_numbers_are_jumpers no)
		(fp_line
			(start -0.7874 0.4064)
			(end 0.7874 0.4064)
			(stroke
				(width 0.1524)
				(type default)
			)
			(layer "B.SilkS")
		)
		(fp_line
			(start 0.7874 0.4064)
			(end 0.7874 -0.4064)
			(stroke
				(width 0.1524)
				(type default)
			)
			(layer "B.SilkS")
		)
		(fp_line
			(start -0.7874 -0.4064)
			(end -0.7874 0.4064)
			(stroke
				(width 0.1524)
				(type default)
			)
			(layer "B.SilkS")
		)
		(fp_line
			(start 0.7874 -0.4064)
			(end -0.7874 -0.4064)
			(stroke
				(width 0.1524)
				(type default)
			)
			(layer "B.SilkS")
		)
		(fp_line
			(start -0.67945 0.3048)
			(end -0.120396 0.3048)
			(stroke
				(width 0.1)
				(type default)
			)
			(layer "B.Fab")
		)
		(fp_line
			(start -0.120396 0.3048)
			(end -0.120396 0.2794)
			(stroke
				(width 0.1)
				(type default)
			)
			(layer "B.Fab")
		)
		(fp_line
			(start 0.12065 0.3048)
			(end 0.67945 0.3048)
			(stroke
				(width 0.1)
				(type default)
			)
			(layer "B.Fab")
		)
		(fp_line
			(start 0.67945 0.3048)
			(end 0.67945 -0.305054)
			(stroke
				(width 0.1)
				(type default)
			)
			(layer "B.Fab")
		)
		(fp_line
			(start -0.120396 0.2794)
			(end 0.12065 0.2794)
			(stroke
				(width 0.1)
				(type default)
			)
			(layer "B.Fab")
		)
		(fp_line
			(start 0.12065 0.2794)
			(end 0.12065 0.3048)
			(stroke
				(width 0.1)
				(type default)
			)
			(layer "B.Fab")
		)
		(fp_line
			(start -0.12065 -0.2794)
			(end -0.12065 -0.3048)
			(stroke
				(width 0.1)
				(type default)
			)
			(layer "B.Fab")
		)
		(fp_line
			(start 0.12065 -0.2794)
			(end -0.12065 -0.2794)
			(stroke
				(width 0.1)
				(type default)
			)
			(layer "B.Fab")
		)
		(fp_line
			(start -0.67945 -0.3048)
			(end -0.67945 0.3048)
			(stroke
				(width 0.1)
				(type default)
			)
			(layer "B.Fab")
		)
		(fp_line
			(start -0.12065 -0.3048)
			(end -0.67945 -0.3048)
			(stroke
				(width 0.1)
				(type default)
			)
			(layer "B.Fab")
		)
		(fp_line
			(start 0.12065 -0.305054)
			(end 0.12065 -0.2794)
			(stroke
				(width 0.1)
				(type default)
			)
			(layer "B.Fab")
		)
		(fp_line
			(start 0.67945 -0.305054)
			(end 0.12065 -0.305054)
			(stroke
				(width 0.1)
				(type default)
			)
			(layer "B.Fab")
		)
		(pad "1" smd circle
			(at 0.40005 0 90)
			(size 0 0)
			(layers "B.Cu" "B.Mask" "B.Paste")
			(net "P1V8_CPU0_RT_1D")
		)
		(pad "2" smd circle
			(at -0.40005 0 90)
			(size 0 0)
			(layers "B.Cu" "B.Mask" "B.Paste")
			(net "GND")
		)
	)
	(footprint ""
		(layer "B.Cu")
		(at 323.679566 -416.899344 90)
		(property "Reference" "C6546"
			(at 0 0 90)
			(layer "B.SilkS")
			(hide yes)
			(effects
				(font
					(size 1.27 1.27)
				)
				(justify mirror)
			)
		)
		(property "Value" ""
			(at 0 0 90)
			(layer "B.Fab")
			(effects
				(font
					(size 1.27 1.27)
				)
				(justify mirror)
			)
		)
		(duplicate_pad_numbers_are_jumpers no)
		(fp_line
			(start 0.299974 -0.150114)
			(end -0.299974 -0.150114)
			(stroke
				(width 0.1)
				(type default)
			)
			(layer "B.Fab")
		)
		(fp_line
			(start -0.299974 -0.150114)
			(end -0.299974 0.150114)
			(stroke
				(width 0.1)
				(type default)
			)
			(layer "B.Fab")
		)
		(fp_line
			(start 0.299974 0.150114)
			(end 0.299974 -0.150114)
			(stroke
				(width 0.1)
				(type default)
			)
			(layer "B.Fab")
		)
		(fp_line
			(start -0.299974 0.150114)
			(end 0.299974 0.150114)
			(stroke
				(width 0.1)
				(type default)
			)
			(layer "B.Fab")
		)
		(pad "1" smd rect
			(at 0.2667 0 270)
			(size 0.3048 0.381)
			(layers "B.Cu" "B.Mask" "B.Paste")
			(net "P5E_CPU0_P1_TX_BUF_C_DN<6>")
		)
		(pad "2" smd rect
			(at -0.2667 0 270)
			(size 0.3048 0.381)
			(layers "B.Cu" "B.Mask" "B.Paste")
			(net "P5E_CPU0_P1_TX_BUF_DN<6>")
		)
	)
	(footprint ""
		(layer "B.Cu")
		(at 67.201034 -198.269352)
		(property "Reference" "R558"
			(at 0 0 0)
			(layer "B.SilkS")
			(hide yes)
			(effects
				(font
					(size 1.27 1.27)
				)
				(justify mirror)
			)
		)
		(property "Value" ""
			(at 0 0 0)
			(layer "B.Fab")
			(effects
				(font
					(size 1.27 1.27)
				)
				(justify mirror)
			)
		)
		(duplicate_pad_numbers_are_jumpers no)
		(fp_line
			(start -0.7874 -0.4064)
			(end -0.7874 0.4064)
			(stroke
				(width 0.1524)
				(type default)
			)
			(layer "B.SilkS")
		)
		(fp_line
			(start -0.7874 0.4064)
			(end 0.7874 0.4064)
			(stroke
				(width 0.1524)
				(type default)
			)
			(layer "B.SilkS")
		)
		(fp_line
			(start 0.7874 -0.4064)
			(end -0.7874 -0.4064)
			(stroke
				(width 0.1524)
				(type default)
			)
			(layer "B.SilkS")
		)
		(fp_line
			(start 0.7874 0.4064)
			(end 0.7874 -0.4064)
			(stroke
				(width 0.1524)
				(type default)
			)
			(layer "B.SilkS")
		)
		(fp_line
			(start -0.67945 -0.3048)
			(end -0.67945 0.3048)
			(stroke
				(width 0.1)
				(type default)
			)
			(layer "B.Fab")
		)
		(fp_line
			(start -0.67945 0.3048)
			(end -0.120396 0.3048)
			(stroke
				(width 0.1)
				(type default)
			)
			(layer "B.Fab")
		)
		(fp_line
			(start -0.12065 -0.3048)
			(end -0.67945 -0.3048)
			(stroke
				(width 0.1)
				(type default)
			)
			(layer "B.Fab")
		)
		(fp_line
			(start -0.12065 -0.2794)
			(end -0.12065 -0.3048)
			(stroke
				(width 0.1)
				(type default)
			)
			(layer "B.Fab")
		)
		(fp_line
			(start -0.120396 0.2794)
			(end 0.12065 0.2794)
			(stroke
				(width 0.1)
				(type default)
			)
			(layer "B.Fab")
		)
		(fp_line
			(start -0.120396 0.3048)
			(end -0.120396 0.2794)
			(stroke
				(width 0.1)
				(type default)
			)
			(layer "B.Fab")
		)
		(fp_line
			(start 0.12065 -0.305054)
			(end 0.12065 -0.2794)
			(stroke
				(width 0.1)
				(type default)
			)
			(layer "B.Fab")
		)
		(fp_line
			(start 0.12065 -0.2794)
			(end -0.12065 -0.2794)
			(stroke
				(width 0.1)
				(type default)
			)
			(layer "B.Fab")
		)
		(fp_line
			(start 0.12065 0.2794)
			(end 0.12065 0.3048)
			(stroke
				(width 0.1)
				(type default)
			)
			(layer "B.Fab")
		)
		(fp_line
			(start 0.12065 0.3048)
			(end 0.67945 0.3048)
			(stroke
				(width 0.1)
				(type default)
			)
			(layer "B.Fab")
		)
		(fp_line
			(start 0.67945 -0.305054)
			(end 0.12065 -0.305054)
			(stroke
				(width 0.1)
				(type default)
			)
			(layer "B.Fab")
		)
		(fp_line
			(start 0.67945 0.3048)
			(end 0.67945 -0.305054)
			(stroke
				(width 0.1)
				(type default)
			)
			(layer "B.Fab")
		)
		(pad "1" smd circle
			(at 0.40005 0 180)
			(size 0 0)
			(layers "B.Cu" "B.Mask" "B.Paste")
			(net "CPU1_FORCE_SELFREFRESH")
		)
		(pad "2" smd circle
			(at -0.40005 0 180)
			(size 0 0)
			(layers "B.Cu" "B.Mask" "B.Paste")
			(net "PVDD18_S5_P1")
		)
	)
	(footprint ""
		(layer "B.Cu")
		(at 108.117386 -253.432564)
		(property "Reference" "C2258"
			(at 0 0 0)
			(layer "B.SilkS")
			(hide yes)
			(effects
				(font
					(size 1.27 1.27)
				)
				(justify mirror)
			)
		)
		(property "Value" ""
			(at 0 0 0)
			(layer "B.Fab")
			(effects
				(font
					(size 1.27 1.27)
				)
				(justify mirror)
			)
		)
		(duplicate_pad_numbers_are_jumpers no)
		(fp_line
			(start -0.7874 -0.4064)
			(end -0.7874 0.4064)
			(stroke
				(width 0.1524)
				(type default)
			)
			(layer "B.SilkS")
		)
		(fp_line
			(start -0.7874 0.4064)
			(end 0.7874 0.4064)
			(stroke
				(width 0.1524)
				(type default)
			)
			(layer "B.SilkS")
		)
		(fp_line
			(start 0.7874 -0.4064)
			(end -0.7874 -0.4064)
			(stroke
				(width 0.1524)
				(type default)
			)
			(layer "B.SilkS")
		)
		(fp_line
			(start 0.7874 0.4064)
			(end 0.7874 -0.4064)
			(stroke
				(width 0.1524)
				(type default)
			)
			(layer "B.SilkS")
		)
		(fp_line
			(start -0.67945 -0.3048)
			(end -0.67945 0.3048)
			(stroke
				(width 0.1)
				(type default)
			)
			(layer "B.Fab")
		)
		(fp_line
			(start -0.67945 0.3048)
			(end -0.120396 0.3048)
			(stroke
				(width 0.1)
				(type default)
			)
			(layer "B.Fab")
		)
		(fp_line
			(start -0.12065 -0.3048)
			(end -0.67945 -0.3048)
			(stroke
				(width 0.1)
				(type default)
			)
			(layer "B.Fab")
		)
		(fp_line
			(start -0.12065 -0.2794)
			(end -0.12065 -0.3048)
			(stroke
				(width 0.1)
				(type default)
			)
			(layer "B.Fab")
		)
		(fp_line
			(start -0.120396 0.2794)
			(end 0.12065 0.2794)
			(stroke
				(width 0.1)
				(type default)
			)
			(layer "B.Fab")
		)
		(fp_line
			(start -0.120396 0.3048)
			(end -0.120396 0.2794)
			(stroke
				(width 0.1)
				(type default)
			)
			(layer "B.Fab")
		)
		(fp_line
			(start 0.12065 -0.305054)
			(end 0.12065 -0.2794)
			(stroke
				(width 0.1)
				(type default)
			)
			(layer "B.Fab")
		)
		(fp_line
			(start 0.12065 -0.2794)
			(end -0.12065 -0.2794)
			(stroke
				(width 0.1)
				(type default)
			)
			(layer "B.Fab")
		)
		(fp_line
			(start 0.12065 0.2794)
			(end 0.12065 0.3048)
			(stroke
				(width 0.1)
				(type default)
			)
			(layer "B.Fab")
		)
		(fp_line
			(start 0.12065 0.3048)
			(end 0.67945 0.3048)
			(stroke
				(width 0.1)
				(type default)
			)
			(layer "B.Fab")
		)
		(fp_line
			(start 0.67945 -0.305054)
			(end 0.12065 -0.305054)
			(stroke
				(width 0.1)
				(type default)
			)
			(layer "B.Fab")
		)
		(fp_line
			(start 0.67945 0.3048)
			(end 0.67945 -0.305054)
			(stroke
				(width 0.1)
				(type default)
			)
			(layer "B.Fab")
		)
		(pad "1" smd circle
			(at 0.40005 0 180)
			(size 0 0)
			(layers "B.Cu" "B.Mask" "B.Paste")
			(net "PVDDCR_SOC_P1")
		)
		(pad "2" smd circle
			(at -0.40005 0 180)
			(size 0 0)
			(layers "B.Cu" "B.Mask" "B.Paste")
			(net "GND")
		)
	)
	(footprint ""
		(layer "B.Cu")
		(at 65.378584 -386.766562 90)
		(property "Reference" "C188"
			(at 0 0 90)
			(layer "B.SilkS")
			(hide yes)
			(effects
				(font
					(size 1.27 1.27)
				)
				(justify mirror)
			)
		)
		(property "Value" ""
			(at 0 0 90)
			(layer "B.Fab")
			(effects
				(font
					(size 1.27 1.27)
				)
				(justify mirror)
			)
		)
		(duplicate_pad_numbers_are_jumpers no)
		(fp_line
			(start 0.299974 -0.150114)
			(end -0.299974 -0.150114)
			(stroke
				(width 0.1)
				(type default)
			)
			(layer "B.Fab")
		)
		(fp_line
			(start -0.299974 -0.150114)
			(end -0.299974 0.150114)
			(stroke
				(width 0.1)
				(type default)
			)
			(layer "B.Fab")
		)
		(fp_line
			(start 0.299974 0.150114)
			(end 0.299974 -0.150114)
			(stroke
				(width 0.1)
				(type default)
			)
			(layer "B.Fab")
		)
		(fp_line
			(start -0.299974 0.150114)
			(end 0.299974 0.150114)
			(stroke
				(width 0.1)
				(type default)
			)
			(layer "B.Fab")
		)
		(pad "1" smd rect
			(at 0.2667 0 270)
			(size 0.3048 0.381)
			(layers "B.Cu" "B.Mask" "B.Paste")
			(net "P0V9_CPU1_RT0_2A")
		)
		(pad "2" smd rect
			(at -0.2667 0 270)
			(size 0.3048 0.381)
			(layers "B.Cu" "B.Mask" "B.Paste")
			(net "GND")
		)
	)
	(footprint ""
		(layer "B.Cu")
		(at 230.891842 -315.95568 -90)
		(property "Reference" "PC6529"
			(at 0 0 90)
			(layer "B.SilkS")
			(hide yes)
			(effects
				(font
					(size 1.27 1.27)
				)
				(justify mirror)
			)
		)
		(property "Value" ""
			(at 0 0 90)
			(layer "B.Fab")
			(effects
				(font
					(size 1.27 1.27)
				)
				(justify mirror)
			)
		)
		(duplicate_pad_numbers_are_jumpers no)
		(fp_line
			(start -1.524 0.762)
			(end 1.524 0.762)
			(stroke
				(width 0.1524)
				(type default)
			)
			(layer "B.SilkS")
		)
		(fp_line
			(start 1.524 0.762)
			(end 1.524 -0.762)
			(stroke
				(width 0.1524)
				(type default)
			)
			(layer "B.SilkS")
		)
		(fp_line
			(start -1.524 -0.762)
			(end -1.524 0.762)
			(stroke
				(width 0.1524)
				(type default)
			)
			(layer "B.SilkS")
		)
		(fp_line
			(start 1.524 -0.762)
			(end -1.524 -0.762)
			(stroke
				(width 0.1524)
				(type default)
			)
			(layer "B.SilkS")
		)
		(fp_line
			(start -1.1049 0.724916)
			(end -1.1049 -0.724916)
			(stroke
				(width 0.1)
				(type default)
			)
			(layer "B.Fab")
		)
		(fp_line
			(start 1.1049 0.724916)
			(end -1.1049 0.724916)
			(stroke
				(width 0.1)
				(type default)
			)
			(layer "B.Fab")
		)
		(fp_line
			(start -1.1049 -0.724916)
			(end 1.1049 -0.724916)
			(stroke
				(width 0.1)
				(type default)
			)
			(layer "B.Fab")
		)
		(fp_line
			(start 1.1049 -0.724916)
			(end 1.1049 0.724916)
			(stroke
				(width 0.1)
				(type default)
			)
			(layer "B.Fab")
		)
		(pad "1" smd rect
			(at 0.889 0 270)
			(size 1.016 1.27)
			(layers "B.Cu" "B.Mask" "B.Paste")
			(net "P1V8_CPU1_RT_1D")
		)
		(pad "2" smd rect
			(at -0.889 0 270)
			(size 1.016 1.27)
			(layers "B.Cu" "B.Mask" "B.Paste")
			(net "GND")
		)
	)
	(footprint ""
		(layer "B.Cu")
		(at 46.434502 -422.527984 90)
		(property "Reference" "R3320"
			(at 0 0 90)
			(layer "B.SilkS")
			(hide yes)
			(effects
				(font
					(size 1.27 1.27)
				)
				(justify mirror)
			)
		)
		(property "Value" ""
			(at 0 0 90)
			(layer "B.Fab")
			(effects
				(font
					(size 1.27 1.27)
				)
				(justify mirror)
			)
		)
		(duplicate_pad_numbers_are_jumpers no)
		(fp_line
			(start 0.7874 -0.4064)
			(end -0.7874 -0.4064)
			(stroke
				(width 0.1524)
				(type default)
			)
			(layer "B.SilkS")
		)
		(fp_line
			(start -0.7874 -0.4064)
			(end -0.7874 0.4064)
			(stroke
				(width 0.1524)
				(type default)
			)
			(layer "B.SilkS")
		)
		(fp_line
			(start 0.7874 0.4064)
			(end 0.7874 -0.4064)
			(stroke
				(width 0.1524)
				(type default)
			)
			(layer "B.SilkS")
		)
		(fp_line
			(start -0.7874 0.4064)
			(end 0.7874 0.4064)
			(stroke
				(width 0.1524)
				(type default)
			)
			(layer "B.SilkS")
		)
		(fp_line
			(start 0.67945 -0.305054)
			(end 0.12065 -0.305054)
			(stroke
				(width 0.1)
				(type default)
			)
			(layer "B.Fab")
		)
		(fp_line
			(start 0.12065 -0.305054)
			(end 0.12065 -0.2794)
			(stroke
				(width 0.1)
				(type default)
			)
			(layer "B.Fab")
		)
		(fp_line
			(start -0.12065 -0.3048)
			(end -0.67945 -0.3048)
			(stroke
				(width 0.1)
				(type default)
			)
			(layer "B.Fab")
		)
		(fp_line
			(start -0.67945 -0.3048)
			(end -0.67945 0.3048)
			(stroke
				(width 0.1)
				(type default)
			)
			(layer "B.Fab")
		)
		(fp_line
			(start 0.12065 -0.2794)
			(end -0.12065 -0.2794)
			(stroke
				(width 0.1)
				(type default)
			)
			(layer "B.Fab")
		)
		(fp_line
			(start -0.12065 -0.2794)
			(end -0.12065 -0.3048)
			(stroke
				(width 0.1)
				(type default)
			)
			(layer "B.Fab")
		)
		(fp_line
			(start 0.12065 0.2794)
			(end 0.12065 0.3048)
			(stroke
				(width 0.1)
				(type default)
			)
			(layer "B.Fab")
		)
		(fp_line
			(start -0.120396 0.2794)
			(end 0.12065 0.2794)
			(stroke
				(width 0.1)
				(type default)
			)
			(layer "B.Fab")
		)
		(fp_line
			(start 0.67945 0.3048)
			(end 0.67945 -0.305054)
			(stroke
				(width 0.1)
				(type default)
			)
			(layer "B.Fab")
		)
		(fp_line
			(start 0.12065 0.3048)
			(end 0.67945 0.3048)
			(stroke
				(width 0.1)
				(type default)
			)
			(layer "B.Fab")
		)
		(fp_line
			(start -0.120396 0.3048)
			(end -0.120396 0.2794)
			(stroke
				(width 0.1)
				(type default)
			)
			(layer "B.Fab")
		)
		(fp_line
			(start -0.67945 0.3048)
			(end -0.120396 0.3048)
			(stroke
				(width 0.1)
				(type default)
			)
			(layer "B.Fab")
		)
		(pad "1" smd circle
			(at 0.40005 0 270)
			(size 0 0)
			(layers "B.Cu" "B.Mask" "B.Paste")
			(net "P3V3_AUX")
		)
		(pad "2" smd circle
			(at -0.40005 0 270)
			(size 0 0)
			(layers "B.Cu" "B.Mask" "B.Paste")
			(net "GPU_FPGA_READY_N")
		)
	)
	(footprint ""
		(layer "B.Cu")
		(at 125.278388 -386.766562 90)
		(property "Reference" "C441"
			(at 0 0 90)
			(layer "B.SilkS")
			(hide yes)
			(effects
				(font
					(size 1.27 1.27)
				)
				(justify mirror)
			)
		)
		(property "Value" ""
			(at 0 0 90)
			(layer "B.Fab")
			(effects
				(font
					(size 1.27 1.27)
				)
				(justify mirror)
			)
		)
		(duplicate_pad_numbers_are_jumpers no)
		(fp_line
			(start 0.299974 -0.150114)
			(end -0.299974 -0.150114)
			(stroke
				(width 0.1)
				(type default)
			)
			(layer "B.Fab")
		)
		(fp_line
			(start -0.299974 -0.150114)
			(end -0.299974 0.150114)
			(stroke
				(width 0.1)
				(type default)
			)
			(layer "B.Fab")
		)
		(fp_line
			(start 0.299974 0.150114)
			(end 0.299974 -0.150114)
			(stroke
				(width 0.1)
				(type default)
			)
			(layer "B.Fab")
		)
		(fp_line
			(start -0.299974 0.150114)
			(end 0.299974 0.150114)
			(stroke
				(width 0.1)
				(type default)
			)
			(layer "B.Fab")
		)
		(pad "1" smd rect
			(at 0.2667 0 270)
			(size 0.3048 0.381)
			(layers "B.Cu" "B.Mask" "B.Paste")
			(net "P1V8_CPU1_RT3_1A_1D")
		)
		(pad "2" smd rect
			(at -0.2667 0 270)
			(size 0.3048 0.381)
			(layers "B.Cu" "B.Mask" "B.Paste")
			(net "GND")
		)
	)
	(footprint ""
		(layer "B.Cu")
		(at 398.893538 -392.1252 180)
		(property "Reference" "R1064"
			(at 0 0 0)
			(layer "B.SilkS")
			(hide yes)
			(effects
				(font
					(size 1.27 1.27)
				)
				(justify mirror)
			)
		)
		(property "Value" ""
			(at 0 0 0)
			(layer "B.Fab")
			(effects
				(font
					(size 1.27 1.27)
				)
				(justify mirror)
			)
		)
		(duplicate_pad_numbers_are_jumpers no)
		(fp_line
			(start 0.32512 0.175006)
			(end 0.32512 -0.175006)
			(stroke
				(width 0.1)
				(type default)
			)
			(layer "B.Fab")
		)
		(fp_line
			(start 0.32512 -0.175006)
			(end -0.32512 -0.175006)
			(stroke
				(width 0.1)
				(type default)
			)
			(layer "B.Fab")
		)
		(fp_line
			(start -0.32512 0.175006)
			(end 0.32512 0.175006)
			(stroke
				(width 0.1)
				(type default)
			)
			(layer "B.Fab")
		)
		(fp_line
			(start -0.32512 -0.175006)
			(end -0.32512 0.175006)
			(stroke
				(width 0.1)
				(type default)
			)
			(layer "B.Fab")
		)
		(pad "1" smd rect
			(at 0.2667 0)
			(size 0.3048 0.381)
			(layers "B.Cu" "B.Mask" "B.Paste")
			(net "RT_CPU0_P2_SCAN_MODE")
		)
		(pad "2" smd rect
			(at -0.2667 0 180)
			(size 0.3048 0.381)
			(layers "B.Cu" "B.Mask" "B.Paste")
			(net "GND")
		)
	)
)
